# S9S_MB_2U (Grand Teton) — schematic netlist excerpt (pin names and nets, part order shuffled) for the footprints in the layout excerpt that follows; sources: Cadence DE-HDL packaged netlist, KiCad conversion of 03242023_DA0F0TMBIJ0_F0T_Motherboard_J_brd_V01_OCP.brd

PC563_P1_1  Q_CAP  1UF 16V 10% X6S  pkg C0402  page 285 : A = SW_P12V_PVCCIN_CPU1_FLT ; B = GND
PR1707  Q_RES  8.87K 1% EMPTY  pkg 0402LF  page 275 : A = PVCCINFAON_CPU0_LSET2 ; B = GND

(kicad_pcb
	(version 20260206)
	(generator "pcbnew")
	(generator_version "10.0")
	(general
		(thickness 1.6)
		(legacy_teardrops no)
	)
	(paper "A4")
	(title_block
		(title "03242023_DA0F0TMBIJ0_F0T_Motherboard_J_brd_V01_OCP.brd")
		(comment 1 "Grand Teton / footprints 2268-2269 of 6105")
	)
	(layers
		(0 "F.Cu" signal "TOP")
		(4 "In1.Cu" signal "GND")
		(6 "In2.Cu" signal "IN1")
		(8 "In3.Cu" signal "GND1")
		(10 "In4.Cu" signal "IN2")
		(12 "In5.Cu" signal "GND2")
		(14 "In6.Cu" signal "IN3")
		(16 "In7.Cu" signal "GND3")
		(18 "In8.Cu" signal "VCC")
		(20 "In9.Cu" signal "VCC1")
		(22 "In10.Cu" signal "GND4")
		(24 "In11.Cu" signal "IN4")
		(26 "In12.Cu" signal "GND5")
		(28 "In13.Cu" signal "IN5")
		(30 "In14.Cu" signal "GND6")
		(32 "In15.Cu" signal "IN6")
		(34 "In16.Cu" signal "GND7")
		(2 "B.Cu" signal "BOTTOM")
		(9 "F.Adhes" user "F.Adhesive")
		(11 "B.Adhes" user "B.Adhesive")
		(13 "F.Paste" user "Package Geometry/Pastemask Top")
		(15 "B.Paste" user "Package Geometry/Pastemask Bottom")
		(5 "F.SilkS" user "Ref Des/Silkscreen Top")
		(7 "B.SilkS" user "Ref Des/Silkscreen Bottom")
		(1 "F.Mask" user "Board Geometry/Soldermask Top")
		(3 "B.Mask" user "Board Geometry/Soldermask Bottom")
		(17 "Dwgs.User" user "User.Drawings")
		(19 "Cmts.User" user "User.Comments")
		(21 "Eco1.User" user "User.Eco1")
		(23 "Eco2.User" user "User.Eco2")
		(25 "Edge.Cuts" user "Board Geometry/Outline")
		(27 "Margin" user)
		(31 "F.CrtYd" user "Package Geometry/Place Bound Top")
		(29 "B.CrtYd" user "Package Geometry/Place Bound Bottom")
		(35 "F.Fab" user "Ref Des/Assembly Top")
		(33 "B.Fab" user "Ref Des/Assembly Bottom")
	)
	(footprint ""
		(layer "F.Cu")
		(at 100.566982 -333.804514 -90)
		(property "Reference" "PC563_P1_1"
			(at 0 0 270)
			(layer "F.SilkS")
			(hide yes)
			(effects
				(font
					(size 1.27 1.27)
				)
			)
		)
		(property "Value" ""
			(at 0 0 270)
			(layer "F.Fab")
			(effects
				(font
					(size 1.27 1.27)
				)
			)
		)
		(duplicate_pad_numbers_are_jumpers no)
		(fp_line
			(start -0.7874 0.4064)
			(end -0.7874 -0.4064)
			(stroke
				(width 0.1524)
				(type default)
			)
			(layer "F.SilkS")
		)
		(fp_line
			(start 0.7874 0.4064)
			(end -0.7874 0.4064)
			(stroke
				(width 0.1524)
				(type default)
			)
			(layer "F.SilkS")
		)
		(fp_line
			(start -0.7874 -0.4064)
			(end 0.7874 -0.4064)
			(stroke
				(width 0.1524)
				(type default)
			)
			(layer "F.SilkS")
		)
		(fp_line
			(start 0.7874 -0.4064)
			(end 0.7874 0.4064)
			(stroke
				(width 0.1524)
				(type default)
			)
			(layer "F.SilkS")
		)
		(fp_line
			(start -0.67945 0.3048)
			(end -0.67945 -0.305054)
			(stroke
				(width 0.1)
				(type default)
			)
			(layer "F.Fab")
		)
		(fp_line
			(start -0.12065 0.3048)
			(end -0.67945 0.3048)
			(stroke
				(width 0.1)
				(type default)
			)
			(layer "F.Fab")
		)
		(fp_line
			(start 0.120396 0.3048)
			(end 0.120396 0.2794)
			(stroke
				(width 0.1)
				(type default)
			)
			(layer "F.Fab")
		)
		(fp_line
			(start 0.67945 0.3048)
			(end 0.120396 0.3048)
			(stroke
				(width 0.1)
				(type default)
			)
			(layer "F.Fab")
		)
		(fp_line
			(start -0.12065 0.2794)
			(end -0.12065 0.3048)
			(stroke
				(width 0.1)
				(type default)
			)
			(layer "F.Fab")
		)
		(fp_line
			(start 0.120396 0.2794)
			(end -0.12065 0.2794)
			(stroke
				(width 0.1)
				(type default)
			)
			(layer "F.Fab")
		)
		(fp_line
			(start -0.12065 -0.2794)
			(end 0.12065 -0.2794)
			(stroke
				(width 0.1)
				(type default)
			)
			(layer "F.Fab")
		)
		(fp_line
			(start 0.12065 -0.2794)
			(end 0.12065 -0.3048)
			(stroke
				(width 0.1)
				(type default)
			)
			(layer "F.Fab")
		)
		(fp_line
			(start 0.12065 -0.3048)
			(end 0.67945 -0.3048)
			(stroke
				(width 0.1)
				(type default)
			)
			(layer "F.Fab")
		)
		(fp_line
			(start 0.67945 -0.3048)
			(end 0.67945 0.3048)
			(stroke
				(width 0.1)
				(type default)
			)
			(layer "F.Fab")
		)
		(fp_line
			(start -0.67945 -0.305054)
			(end -0.12065 -0.305054)
			(stroke
				(width 0.1)
				(type default)
			)
			(layer "F.Fab")
		)
		(fp_line
			(start -0.12065 -0.305054)
			(end -0.12065 -0.2794)
			(stroke
				(width 0.1)
				(type default)
			)
			(layer "F.Fab")
		)
		(pad "1" smd circle
			(at -0.40005 0 270)
			(size 0 0)
			(layers "F.Cu" "F.Mask" "F.Paste")
			(net "SW_P12V_PVCCIN_CPU1_FLT")
		)
		(pad "2" smd circle
			(at 0.40005 0 270)
			(size 0 0)
			(layers "F.Cu" "F.Mask" "F.Paste")
			(net "GND")
		)
	)
	(footprint ""
		(layer "F.Cu")
		(at 421.15359 -180.749194 -90)
		(property "Reference" "PR1707"
			(at 0 0 270)
			(layer "F.SilkS")
			(hide yes)
			(effects
				(font
					(size 1.27 1.27)
				)
			)
		)
		(property "Value" ""
			(at 0 0 270)
			(layer "F.Fab")
			(effects
				(font
					(size 1.27 1.27)
				)
			)
		)
		(duplicate_pad_numbers_are_jumpers no)
		(fp_line
			(start -0.7874 0.4064)
			(end -0.7874 -0.4064)
			(stroke
				(width 0.1524)
				(type default)
			)
			(layer "F.SilkS")
		)
		(fp_line
			(start 0.7874 0.4064)
			(end -0.7874 0.4064)
			(stroke
				(width 0.1524)
				(type default)
			)
			(layer "F.SilkS")
		)
		(fp_line
			(start -0.7874 -0.4064)
			(end 0.7874 -0.4064)
			(stroke
				(width 0.1524)
				(type default)
			)
			(layer "F.SilkS")
		)
		(fp_line
			(start 0.7874 -0.4064)
			(end 0.7874 0.4064)
			(stroke
				(width 0.1524)
				(type default)
			)
			(layer "F.SilkS")
		)
		(fp_line
			(start -0.67945 0.3048)
			(end -0.67945 -0.305054)
			(stroke
				(width 0.1)
				(type default)
			)
			(layer "F.Fab")
		)
		(fp_line
			(start -0.12065 0.3048)
			(end -0.67945 0.3048)
			(stroke
				(width 0.1)
				(type default)
			)
			(layer "F.Fab")
		)
		(fp_line
			(start 0.120396 0.3048)
			(end 0.120396 0.2794)
			(stroke
				(width 0.1)
				(type default)
			)
			(layer "F.Fab")
		)
		(fp_line
			(start 0.67945 0.3048)
			(end 0.120396 0.3048)
			(stroke
				(width 0.1)
				(type default)
			)
			(layer "F.Fab")
		)
		(fp_line
			(start -0.12065 0.2794)
			(end -0.12065 0.3048)
			(stroke
				(width 0.1)
				(type default)
			)
			(layer "F.Fab")
		)
		(fp_line
			(start 0.120396 0.2794)
			(end -0.12065 0.2794)
			(stroke
				(width 0.1)
				(type default)
			)
			(layer "F.Fab")
		)
		(fp_line
			(start -0.12065 -0.2794)
			(end 0.12065 -0.2794)
			(stroke
				(width 0.1)
				(type default)
			)
			(layer "F.Fab")
		)
		(fp_line
			(start 0.12065 -0.2794)
			(end 0.12065 -0.3048)
			(stroke
				(width 0.1)
				(type default)
			)
			(layer "F.Fab")
		)
		(fp_line
			(start 0.12065 -0.3048)
			(end 0.67945 -0.3048)
			(stroke
				(width 0.1)
				(type default)
			)
			(layer "F.Fab")
		)
		(fp_line
			(start 0.67945 -0.3048)
			(end 0.67945 0.3048)
			(stroke
				(width 0.1)
				(type default)
			)
			(layer "F.Fab")
		)
		(fp_line
			(start -0.67945 -0.305054)
			(end -0.12065 -0.305054)
			(stroke
				(width 0.1)
				(type default)
			)
			(layer "F.Fab")
		)
		(fp_line
			(start -0.12065 -0.305054)
			(end -0.12065 -0.2794)
			(stroke
				(width 0.1)
				(type default)
			)
			(layer "F.Fab")
		)
		(pad "1" smd circle
			(at -0.40005 0 270)
			(size 0 0)
			(layers "F.Cu" "F.Mask" "F.Paste")
			(net "PVCCINFAON_CPU0_LSET2")
		)
		(pad "2" smd circle
			(at 0.40005 0 270)
			(size 0 0)
			(layers "F.Cu" "F.Mask" "F.Paste")
			(net "GND")
		)
	)
)
